# T6G (Grand Teton) — schematic netlist excerpt (pin names and nets, part order shuffled) for the footprints in the layout excerpt that follows; sources: Cadence DE-HDL packaged netlist, KiCad conversion of 04192023_DAF0TMB3IC0_F0TG_MB_C_brd_V02_OCP.brd

R962  Q_RES  0 5% CHIP  pkg 0603LF  page 279 : A = P0V9_CPU0_RT0_2A_2D ; B = P0V9_CPU0_RT0_2A

U190  MOSFET_NCH_GDS_ESD_PROTECTED  2N7002K IC  pkg SOT23_GDSXC  page 240
  D  = FM_PDB_BUF_EN_R1
  G  = FM_PDB_BUF_EN_R1_N
  S  = GND

(kicad_pcb
	(version 20260206)
	(generator "pcbnew")
	(generator_version "10.0")
	(general
		(thickness 1.6)
		(legacy_teardrops no)
	)
	(paper "A4")
	(title_block
		(title "04192023_DAF0TMB3IC0_F0TG_MB_C_brd_V02_OCP.brd")
		(comment 1 "Grand Teton / footprints 306-307 of 8354")
	)
	(layers
		(0 "F.Cu" signal "TOP")
		(4 "In1.Cu" signal "GND")
		(6 "In2.Cu" signal "IN1")
		(8 "In3.Cu" signal "GND1")
		(10 "In4.Cu" signal "IN2")
		(12 "In5.Cu" signal "GND2")
		(14 "In6.Cu" signal "IN3")
		(16 "In7.Cu" signal "GND3")
		(18 "In8.Cu" signal "VCC")
		(20 "In9.Cu" signal "VCC1")
		(22 "In10.Cu" signal "GND4")
		(24 "In11.Cu" signal "IN4")
		(26 "In12.Cu" signal "GND5")
		(28 "In13.Cu" signal "IN5")
		(30 "In14.Cu" signal "GND6")
		(32 "In15.Cu" signal "IN6")
		(34 "In16.Cu" signal "GND7")
		(2 "B.Cu" signal "BOTTOM")
		(9 "F.Adhes" user "F.Adhesive")
		(11 "B.Adhes" user "B.Adhesive")
		(13 "F.Paste" user "Package Geometry/Pastemask Top")
		(15 "B.Paste" user "Package Geometry/Pastemask Bottom")
		(5 "F.SilkS" user "Ref Des/Silkscreen Top")
		(7 "B.SilkS" user "Ref Des/Silkscreen Bottom")
		(1 "F.Mask" user "Board Geometry/Soldermask Top")
		(3 "B.Mask" user "Board Geometry/Soldermask Bottom")
		(17 "Dwgs.User" user "User.Drawings")
		(19 "Cmts.User" user "User.Comments")
		(21 "Eco1.User" user "User.Eco1")
		(23 "Eco2.User" user "User.Eco2")
		(25 "Edge.Cuts" user "Board Geometry/Outline")
		(27 "Margin" user)
		(31 "F.CrtYd" user "Package Geometry/Place Bound Top")
		(29 "B.CrtYd" user "Package Geometry/Place Bound Bottom")
		(35 "F.Fab" user "Ref Des/Assembly Top")
		(33 "B.Fab" user "Ref Des/Assembly Bottom")
	)
	(footprint ""
		(layer "F.Cu")
		(at 193.369438 -427.693328 -90)
		(property "Reference" "U190"
			(at 2.258568 1.78308 0)
			(unlocked yes)
			(layer "F.SilkS")
			(effects
				(font
					(size 0.7874 0.5842)
					(thickness 0.1524)
				)
				(justify left)
			)
		)
		(property "Value" ""
			(at 0 0 270)
			(layer "F.Fab")
			(effects
				(font
					(size 1.27 1.27)
				)
			)
		)
		(duplicate_pad_numbers_are_jumpers no)
		(fp_line
			(start -1.603248 1.500124)
			(end -1.603248 -1.500124)
			(stroke
				(width 0.1524)
				(type default)
			)
			(layer "F.SilkS")
		)
		(fp_line
			(start 1.603248 1.500124)
			(end -1.603248 1.500124)
			(stroke
				(width 0.1524)
				(type default)
			)
			(layer "F.SilkS")
		)
		(fp_line
			(start -1.603248 -1.500124)
			(end 1.603248 -1.500124)
			(stroke
				(width 0.1524)
				(type default)
			)
			(layer "F.SilkS")
		)
		(fp_line
			(start 1.603248 -1.500124)
			(end 1.603248 1.500124)
			(stroke
				(width 0.1524)
				(type default)
			)
			(layer "F.SilkS")
		)
		(fp_line
			(start -0.700024 1.500124)
			(end 0.700024 1.500124)
			(stroke
				(width 0.1)
				(type default)
			)
			(layer "F.Fab")
		)
		(fp_line
			(start 0.700024 1.500124)
			(end 0.700024 0.219964)
			(stroke
				(width 0.1)
				(type default)
			)
			(layer "F.Fab")
		)
		(fp_line
			(start -1.249934 1.169924)
			(end -0.700024 1.169924)
			(stroke
				(width 0.1)
				(type default)
			)
			(layer "F.Fab")
		)
		(fp_line
			(start -0.700024 1.169924)
			(end -0.700024 1.500124)
			(stroke
				(width 0.1)
				(type default)
			)
			(layer "F.Fab")
		)
		(fp_line
			(start -1.249934 0.729996)
			(end -1.249934 1.169924)
			(stroke
				(width 0.1)
				(type default)
			)
			(layer "F.Fab")
		)
		(fp_line
			(start -0.6985 0.729996)
			(end -1.249934 0.729996)
			(stroke
				(width 0.1)
				(type default)
			)
			(layer "F.Fab")
		)
		(fp_line
			(start 0.700024 0.219964)
			(end 1.249934 0.219964)
			(stroke
				(width 0.1)
				(type default)
			)
			(layer "F.Fab")
		)
		(fp_line
			(start 1.249934 0.219964)
			(end 1.249934 -0.219964)
			(stroke
				(width 0.1)
				(type default)
			)
			(layer "F.Fab")
		)
		(fp_line
			(start 0.700024 -0.219964)
			(end 0.700024 -1.500124)
			(stroke
				(width 0.1)
				(type default)
			)
			(layer "F.Fab")
		)
		(fp_line
			(start 1.249934 -0.219964)
			(end 0.700024 -0.219964)
			(stroke
				(width 0.1)
				(type default)
			)
			(layer "F.Fab")
		)
		(fp_line
			(start -1.249934 -0.729996)
			(end -0.6985 -0.729996)
			(stroke
				(width 0.1)
				(type default)
			)
			(layer "F.Fab")
		)
		(fp_line
			(start -0.6985 -0.729996)
			(end -0.6985 0.729996)
			(stroke
				(width 0.1)
				(type default)
			)
			(layer "F.Fab")
		)
		(fp_line
			(start -1.249934 -1.169924)
			(end -1.249934 -0.729996)
			(stroke
				(width 0.1)
				(type default)
			)
			(layer "F.Fab")
		)
		(fp_line
			(start -0.700024 -1.169924)
			(end -1.249934 -1.169924)
			(stroke
				(width 0.1)
				(type default)
			)
			(layer "F.Fab")
		)
		(fp_line
			(start -0.700024 -1.500124)
			(end -0.700024 -1.169924)
			(stroke
				(width 0.1)
				(type default)
			)
			(layer "F.Fab")
		)
		(fp_line
			(start 0.700024 -1.500124)
			(end -0.700024 -1.500124)
			(stroke
				(width 0.1)
				(type default)
			)
			(layer "F.Fab")
		)
		(fp_rect
			(start -0.700024 1.500124)
			(end 0.700024 -1.500124)
			(stroke
				(width 0)
				(type default)
			)
			(fill no)
			(layer "F.Fab")
		)
		(pad "D" smd rect
			(at 0.999998 0 180)
			(size 0.8128 0.9144)
			(layers "F.Cu" "F.Mask" "F.Paste")
			(net "FM_PDB_BUF_EN_R1")
		)
		(pad "G" smd rect
			(at -0.999998 -0.94996 180)
			(size 0.8128 0.9144)
			(layers "F.Cu" "F.Mask" "F.Paste")
			(net "FM_PDB_BUF_EN_R1_N")
		)
		(pad "S" smd rect
			(at -0.999998 0.94996 180)
			(size 0.8128 0.9144)
			(layers "F.Cu" "F.Mask" "F.Paste")
			(net "GND")
		)
	)
	(footprint ""
		(layer "F.Cu")
		(at 302.09617 -407.79446)
		(property "Reference" "R962"
			(at 0 0 0)
			(layer "F.SilkS")
			(hide yes)
			(effects
				(font
					(size 1.27 1.27)
				)
			)
		)
		(property "Value" ""
			(at 0 0 0)
			(layer "F.Fab")
			(effects
				(font
					(size 1.27 1.27)
				)
			)
		)
		(duplicate_pad_numbers_are_jumpers no)
		(fp_line
			(start -1.2954 -0.5842)
			(end 1.2954 -0.5842)
			(stroke
				(width 0.1524)
				(type default)
			)
			(layer "F.SilkS")
		)
		(fp_line
			(start -1.2954 0.5842)
			(end -1.2954 -0.5842)
			(stroke
				(width 0.1524)
				(type default)
			)
			(layer "F.SilkS")
		)
		(fp_line
			(start 1.2954 -0.5842)
			(end 1.2954 0.5842)
			(stroke
				(width 0.1524)
				(type default)
			)
			(layer "F.SilkS")
		)
		(fp_line
			(start 1.2954 0.5842)
			(end -1.2954 0.5842)
			(stroke
				(width 0.1524)
				(type default)
			)
			(layer "F.SilkS")
		)
		(fp_line
			(start -1.1938 -0.406654)
			(end -0.8636 -0.406654)
			(stroke
				(width 0.1)
				(type default)
			)
			(layer "F.Fab")
		)
		(fp_line
			(start -1.1938 0.4064)
			(end -1.1938 -0.406654)
			(stroke
				(width 0.1)
				(type default)
			)
			(layer "F.Fab")
		)
		(fp_line
			(start -0.8636 -0.4572)
			(end 0.8636 -0.4572)
			(stroke
				(width 0.1)
				(type default)
			)
			(layer "F.Fab")
		)
		(fp_line
			(start -0.8636 -0.406654)
			(end -0.8636 -0.4572)
			(stroke
				(width 0.1)
				(type default)
			)
			(layer "F.Fab")
		)
		(fp_line
			(start -0.8636 0.4064)
			(end -1.1938 0.4064)
			(stroke
				(width 0.1)
				(type default)
			)
			(layer "F.Fab")
		)
		(fp_line
			(start -0.8636 0.4318)
			(end -0.8636 0.4064)
			(stroke
				(width 0.1)
				(type default)
			)
			(layer "F.Fab")
		)
		(fp_line
			(start -0.8636 0.4572)
			(end -0.8636 0.4318)
			(stroke
				(width 0.1)
				(type default)
			)
			(layer "F.Fab")
		)
		(fp_line
			(start 0.8636 -0.4572)
			(end 0.8636 -0.406654)
			(stroke
				(width 0.1)
				(type default)
			)
			(layer "F.Fab")
		)
		(fp_line
			(start 0.8636 -0.406654)
			(end 1.1938 -0.406654)
			(stroke
				(width 0.1)
				(type default)
			)
			(layer "F.Fab")
		)
		(fp_line
			(start 0.8636 0.4064)
			(end 0.8636 0.4572)
			(stroke
				(width 0.1)
				(type default)
			)
			(layer "F.Fab")
		)
		(fp_line
			(start 0.8636 0.4572)
			(end -0.8636 0.4572)
			(stroke
				(width 0.1)
				(type default)
			)
			(layer "F.Fab")
		)
		(fp_line
			(start 1.1938 -0.406654)
			(end 1.1938 0.4064)
			(stroke
				(width 0.1)
				(type default)
			)
			(layer "F.Fab")
		)
		(fp_line
			(start 1.1938 0.4064)
			(end 0.8636 0.4064)
			(stroke
				(width 0.1)
				(type default)
			)
			(layer "F.Fab")
		)
		(pad "1" smd rect
			(at -0.7366 0 270)
			(size 0.7112 0.8128)
			(layers "F.Cu" "F.Mask" "F.Paste")
			(net "P0V9_CPU0_RT0_2A_2D")
		)
		(pad "2" smd rect
			(at 0.7366 0 270)
			(size 0.7112 0.8128)
			(layers "F.Cu" "F.Mask" "F.Paste")
			(net "P0V9_CPU0_RT0_2A")
		)
	)
)
